# S9S_MB_2U (Grand Teton) — schematic netlist excerpt (pin names and nets, part order shuffled) for the footprints in the layout excerpt that follows; sources: Cadence DE-HDL packaged netlist, KiCad conversion of 03242023_DA0F0TMBIJ0_F0T_Motherboard_J_brd_V01_OCP.brd

J9  SCONN288_ADR50017P130CC  SCONN288_ADR50017-P130CC IO  pkg DDR288S_1-1VXB  page 90
  VIN_BULK0  = P12V_S3_AUX_CPU0_NVDIMM
  RFU0  = TP_CHE_CPU0_DIMM1_FRU_0
  VIN_MGMT  = P3V3_AUX
  HSCL  = I3C_SPD_DDREFGH_CPU0_LVC1_SCL_R
  HSDA  = I3C_SPD_DDREFGH_CPU0_LVC1_SDA
  VSS0  = GND
  DQ0_A  = M_E_CPU0_SA_DQ<0>
  VSS1  = GND
  DQ1_A  = M_E_CPU0_SA_DQ<1>
  VSS2  = GND
  DQS0_A_T  = M_E_CPU0_SA_DQS_DP<0>
  DQS0_A_C  = M_E_CPU0_SA_DQS_DN<0>
  VSS3  = GND
  DQ4_A  = M_E_CPU0_SA_DQ<4>
  VSS4  = GND
  DQ5_A  = M_E_CPU0_SA_DQ<5>
  VSS5  = GND
  DQ8_A  = M_E_CPU0_SA_DQ<8>
  VSS6  = GND
  DQ9_A  = M_E_CPU0_SA_DQ<9>
  VSS7  = GND
  DQS1_A_T  = M_E_CPU0_SA_DQS_DP<1>
  DQS1_A_C  = M_E_CPU0_SA_DQS_DN<1>
  VSS8  = GND
  DQ12_A  = M_E_CPU0_SA_DQ<12>
  VSS9  = GND
  DQ13_A  = M_E_CPU0_SA_DQ<13>
  VSS10  = GND
  DQ16_A  = M_E_CPU0_SA_DQ<16>
  VSS11  = GND
  DQ17_A  = M_E_CPU0_SA_DQ<17>
  VSS12  = GND
  DQS2_A_T  = M_E_CPU0_SA_DQS_DP<2>
  DQS2_A_C  = M_E_CPU0_SA_DQS_DN<2>
  VSS13  = GND
  DQ20_A  = M_E_CPU0_SA_DQ<20>
  VSS14  = GND
  DQ21_A  = M_E_CPU0_SA_DQ<21>
  VSS15  = GND
  DQ24_A  = M_E_CPU0_SA_DQ<24>
  VSS16  = GND
  DQ25_A  = M_E_CPU0_SA_DQ<25>
  VSS17  = GND
  DQS3_A_T  = M_E_CPU0_SA_DQS_DP<3>
  DQS3_A_C  = M_E_CPU0_SA_DQS_DN<3>
  VSS18  = GND
  DQ28_A  = M_E_CPU0_SA_DQ<28>
  VSS19  = GND
  DQ29_A  = M_E_CPU0_SA_DQ<29>
  VSS20  = GND
  CB0_A  = M_E_CPU0_SA_CB<0>
  VSS21  = GND
  CB1_A  = M_E_CPU0_SA_CB<1>
  VSS22  = GND
  DQS4_A_T  = M_E_CPU0_SA_DQS_DP<4>
  DQS4_A_C  = M_E_CPU0_SA_DQS_DN<4>
  VSS23  = GND
  CB4_A  = M_E_CPU0_SA_CB<4>
  VSS24  = GND
  CB5_A  = M_E_CPU0_SA_CB<5>
  VSS25  = GND
  ALERT_N  = M_E_CPU0_ALERT_N
  VSS26  = GND
  CS0_A_N  = M_E_CPU0_SA_CS_N<0>
  VSS27  = GND
  CA0_A  = M_E_CPU0_SA_CA<0>
  VSS28  = GND
  CA2_A  = M_E_CPU0_SA_CA<2>
  VSS29  = GND
  CA4_A  = M_E_CPU0_SA_CA<4>
  VSS30  = GND
  CA6_A  = M_E_CPU0_SA_CA<6>
  VSS31  = GND
  PAR_A  = M_E_CPU0_SA_PAR
  VSS32  = GND
  CA0_B  = M_E_CPU0_SB_CA<0>
  VSS33  = GND
  CA2_B  = M_E_CPU0_SB_CA<2>
  VSS34  = GND
  CA4_B  = M_E_CPU0_SB_CA<4>
  VSS35  = GND
  CA6_B  = M_E_CPU0_SB_CA<6>
  VSS36  = GND
  CS0_B_N  = M_E_CPU0_SB_CS_N<0>
  VSS37  = GND
  \lbd||rsp_a_n\  = M_E_CPU0_SA_RSP<0>
  \lbs||rsp_b_n\  = M_E_CPU0_SB_RSP<0>
  VSS38  = GND
  CB4_B  = M_E_CPU0_SB_CB<4>
  VSS39  = GND
  CB5_B  = M_E_CPU0_SB_CB<5>
  VSS40  = GND
  \dqs9_b_t||tdqs9_b_t||dbi4_b_n\  = M_E_CPU0_SB_DQS_DP<9>
  \dqs9_b_c||tdqs9_b_c\  = M_E_CPU0_SB_DQS_DN<9>
  VSS41  = GND
  CB0_B  = M_E_CPU0_SB_CB<0>
  VSS42  = GND
  CB1_B  = M_E_CPU0_SB_CB<1>
  VSS43  = GND
  DQ0_B  = M_E_CPU0_SB_DQ<0>
  VSS44  = GND
  DQ1_B  = M_E_CPU0_SB_DQ<1>
  VSS45  = GND
  DQS0_B_T  = M_E_CPU0_SB_DQS_DP<0>
  DQS0_B_C  = M_E_CPU0_SB_DQS_DN<0>
  VSS46  = GND
  DQ4_B  = M_E_CPU0_SB_DQ<4>
  VSS47  = GND
  DQ5_B  = M_E_CPU0_SB_DQ<5>
  VSS48  = GND
  DQ8_B  = M_E_CPU0_SB_DQ<8>
  VSS49  = GND
  DQ9_B  = M_E_CPU0_SB_DQ<9>
  VSS50  = GND
  DQS1_B_T  = M_E_CPU0_SB_DQS_DP<1>
  DQS1_B_C  = M_E_CPU0_SB_DQS_DN<1>
  VSS51  = GND
  DQ12_B  = M_E_CPU0_SB_DQ<12>
  VSS52  = GND
  DQ13_B  = M_E_CPU0_SB_DQ<13>
  VSS53  = GND
  DQ16_B  = M_E_CPU0_SB_DQ<16>
  VSS54  = GND
  DQ17_B  = M_E_CPU0_SB_DQ<17>
  VSS55  = GND
  DQS2_B_T  = M_E_CPU0_SB_DQS_DP<2>
  DQS2_B_C  = M_E_CPU0_SB_DQS_DN<2>
  VSS56  = GND
  DQ20_B  = M_E_CPU0_SB_DQ<20>
  VSS57  = GND
  DQ21_B  = M_E_CPU0_SB_DQ<21>
  VSS58  = GND
  DQ24_B  = M_E_CPU0_SB_DQ<24>
  VSS59  = GND
  DQ25_B  = M_E_CPU0_SB_DQ<25>
  VSS60  = GND
  DQS3_B_T  = M_E_CPU0_SB_DQS_DP<3>
  DQS3_B_C  = M_E_CPU0_SB_DQS_DN<3>
  VSS61  = GND
  DQ28_B  = M_E_CPU0_SB_DQ<28>
  VSS62  = GND
  DQ29_B  = M_E_CPU0_SB_DQ<29>
  VSS63  = GND
  RFU1  = TP_CHE_CPU0_DIMM1_FRU_1
  VIN_BULK1  = P12V_S3_AUX_CPU0_NVDIMM
  VIN_BULK2  = P12V_S3_AUX_CPU0_NVDIMM
  \pwr_good||fail_n\  = PWRGD_CHE_CPU0_DIMM1
  HSA  = PD_CHE_CPU0_DIMM1_SAA
  RFU2  = TP_CHE_CPU0_DIMM1_FRU_2
  RFU3  = TP_CHE_CPU0_DIMM1_FRU_3
  VSS64  = GND
  DQ2_A  = M_E_CPU0_SA_DQ<2>
  VSS65  = GND
  DQ3_A  = M_E_CPU0_SA_DQ<3>
  VSS66  = GND
  \dqs5_a_c||tdqs5_a_c||dqs5_a_t||tdqs5_a_t\  = M_E_CPU0_SA_DQS_DN<5>
  \dqs5_a_t||tdqs5_a_t\  = M_E_CPU0_SA_DQS_DP<5>
  VSS67  = GND
  DQ6_A  = M_E_CPU0_SA_DQ<6>
  VSS68  = GND
  DQ7_A  = M_E_CPU0_SA_DQ<7>
  VSS69  = GND
  DQ10_A  = M_E_CPU0_SA_DQ<10>
  VSS70  = GND
  DQ11_A  = M_E_CPU0_SA_DQ<11>
  VSS71  = GND
  \dqs6_a_c||tdqs6_a_c||dqs6_a_t||tdqs6_a_t\  = M_E_CPU0_SA_DQS_DN<6>
  \dqs6_a_t||tdqs6_a_t\  = M_E_CPU0_SA_DQS_DP<6>
  VSS72  = GND
  DQ14_A  = M_E_CPU0_SA_DQ<14>
  VSS73  = GND
  DQ15_A  = M_E_CPU0_SA_DQ<15>
  VSS74  = GND
  DQ18_A  = M_E_CPU0_SA_DQ<18>
  VSS75  = GND
  DQ19_A  = M_E_CPU0_SA_DQ<19>
  VSS76  = GND
  \dqs7_a_c||tdqs7_a_c\  = M_E_CPU0_SA_DQS_DN<7>
  \dqs7_a_t||tdqs7_a_t\  = M_E_CPU0_SA_DQS_DP<7>
  VSS77  = GND
  DQ22_A  = M_E_CPU0_SA_DQ<22>
  VSS78  = GND
  DQ23_A  = M_E_CPU0_SA_DQ<23>
  VSS79  = GND
  DQ26_A  = M_E_CPU0_SA_DQ<26>
  VSS80  = GND
  DQ27_A  = M_E_CPU0_SA_DQ<27>
  VSS81  = GND
  \dqs8_a_c||tdqs8_a_c\  = M_E_CPU0_SA_DQS_DN<8>
  \dqs8_a_t||tdqs8_a_t\  = M_E_CPU0_SA_DQS_DP<8>
  VSS82  = GND
  DQ30_A  = M_E_CPU0_SA_DQ<30>
  VSS83  = GND
  DQ31_A  = M_E_CPU0_SA_DQ<31>
  VSS84  = GND
  CB2_A  = M_E_CPU0_SA_CB<2>
  VSS85  = GND
  CB3_A  = M_E_CPU0_SA_CB<3>
  VSS86  = GND
  \dqs9_a_c||tdqs9_a_c\  = M_E_CPU0_SA_DQS_DN<9>
  \dqs9_a_t||tdqs9_a_t\  = M_E_CPU0_SA_DQS_DP<9>
  VSS87  = GND
  CB6_A  = M_E_CPU0_SA_CB<6>
  VSS88  = GND
  CB7_A  = M_E_CPU0_SA_CB<7>
  VSS89  = GND
  RESET_N  = RST_M_EF_CPU0_FPGA_N
  VSS90  = GND
  CS1_A_N  = M_E_CPU0_SA_CS_N<1>
  VSS91  = GND
  CA1_A  = M_E_CPU0_SA_CA<1>
  VSS92  = GND
  CA3_A  = M_E_CPU0_SA_CA<3>
  VSS93  = GND
  CA5_A  = M_E_CPU0_SA_CA<5>
  VSS94  = GND
  CK_T  = M_E_CPU0_CLK_DP<0>
  CK_C  = M_E_CPU0_CLK_DN<0>
  VSS95  = GND
  RFU4  = TP_CHE_CPU0_DIMM1_FRU_4
  CA1_B  = M_E_CPU0_SB_CA<1>
  VSS96  = GND
  CA3_B  = M_E_CPU0_SB_CA<3>
  VSS97  = GND
  CA5_B  = M_E_CPU0_SB_CA<5>
  VSS98  = GND
  PAR_B  = M_E_CPU0_SB_PAR
  VSS99  = GND
  CS1_B_N  = M_E_CPU0_SB_CS_N<1>
  VSS100  = GND
  RFU5  = TP_CHE_CPU0_DIMM1_FRU_5
  RFU6  = TP_CHE_CPU0_DIMM1_FRU_6
  VSS101  = GND
  CB6_B  = M_E_CPU0_SB_CB<6>
  VSS102  = GND
  CB7_B  = M_E_CPU0_SB_CB<7>
  VSS103  = GND
  DQS4_B_C  = M_E_CPU0_SB_DQS_DN<4>
  DQS4_B_T  = M_E_CPU0_SB_DQS_DP<4>
  VSS104  = GND
  CB2_B  = M_E_CPU0_SB_CB<2>
  VSS105  = GND
  CB3_B  = M_E_CPU0_SB_CB<3>
  VSS106  = GND
  DQ2_B  = M_E_CPU0_SB_DQ<2>
  VSS107  = GND
  DQ3_B  = M_E_CPU0_SB_DQ<3>
  VSS108  = GND
  \dqs5_b_c||tdqs5_b_c\  = M_E_CPU0_SB_DQS_DN<5>
  \dqs5_b_t||tdqs5_b_t\  = M_E_CPU0_SB_DQS_DP<5>
  VSS109  = GND
  DQ6_B  = M_E_CPU0_SB_DQ<6>
  VSS110  = GND
  DQ7_B  = M_E_CPU0_SB_DQ<7>
  VSS111  = GND
  DQ10_B  = M_E_CPU0_SB_DQ<10>
  VSS112  = GND
  DQ11_B  = M_E_CPU0_SB_DQ<11>
  VSS113  = GND
  \dqs6_b_c||tdqs6_b_c\  = M_E_CPU0_SB_DQS_DN<6>
  \dqs6_b_t||tdqs6_b_t\  = M_E_CPU0_SB_DQS_DP<6>
  VSS114  = GND
  DQ14_B  = M_E_CPU0_SB_DQ<14>
  VSS115  = GND
  DQ15_B  = M_E_CPU0_SB_DQ<15>
  VSS116  = GND
  DQ18_B  = M_E_CPU0_SB_DQ<18>
  VSS117  = GND
  DQ19_B  = M_E_CPU0_SB_DQ<19>
  VSS118  = GND
  \dqs7_b_c||tdqs7_b_c\  = M_E_CPU0_SB_DQS_DN<7>
  \dqs7_b_t||tdqs7_b_t\  = M_E_CPU0_SB_DQS_DP<7>
  VSS119  = GND
  DQ22_B  = M_E_CPU0_SB_DQ<22>
  VSS120  = GND
  DQ23_B  = M_E_CPU0_SB_DQ<23>
  VSS121  = GND
  DQ26_B  = M_E_CPU0_SB_DQ<26>
  VSS122  = GND
  DQ27_B  = M_E_CPU0_SB_DQ<27>
  VSS123  = GND
  \dqs8_b_c||tdqs8_b_c\  = M_E_CPU0_SB_DQS_DN<8>
  \dqs8_b_t||tdqs8_b_t\  = M_E_CPU0_SB_DQS_DP<8>
  VSS124  = GND
  DQ30_B  = M_E_CPU0_SB_DQ<30>
  VSS125  = GND
  DQ31_B  = M_E_CPU0_SB_DQ<31>
  VSS126  = GND
  G1  = GND
  G2  = GND
  G3  = GND

(kicad_pcb
	(version 20260206)
	(generator "pcbnew")
	(generator_version "10.0")
	(general
		(thickness 1.6)
		(legacy_teardrops no)
	)
	(paper "A4")
	(title_block
		(title "03242023_DA0F0TMBIJ0_F0T_Motherboard_J_brd_V01_OCP.brd")
		(comment 1 "Grand Teton / footprint 461 of 6105 (J9), pads 92-137 of 291")
	)
	(layers
		(0 "F.Cu" signal "TOP")
		(4 "In1.Cu" signal "GND")
		(6 "In2.Cu" signal "IN1")
		(8 "In3.Cu" signal "GND1")
		(10 "In4.Cu" signal "IN2")
		(12 "In5.Cu" signal "GND2")
		(14 "In6.Cu" signal "IN3")
		(16 "In7.Cu" signal "GND3")
		(18 "In8.Cu" signal "VCC")
		(20 "In9.Cu" signal "VCC1")
		(22 "In10.Cu" signal "GND4")
		(24 "In11.Cu" signal "IN4")
		(26 "In12.Cu" signal "GND5")
		(28 "In13.Cu" signal "IN5")
		(30 "In14.Cu" signal "GND6")
		(32 "In15.Cu" signal "IN6")
		(34 "In16.Cu" signal "GND7")
		(2 "B.Cu" signal "BOTTOM")
		(9 "F.Adhes" user "F.Adhesive")
		(11 "B.Adhes" user "B.Adhesive")
		(13 "F.Paste" user "Package Geometry/Pastemask Top")
		(15 "B.Paste" user "Package Geometry/Pastemask Bottom")
		(5 "F.SilkS" user "Ref Des/Silkscreen Top")
		(7 "B.SilkS" user "Ref Des/Silkscreen Bottom")
		(1 "F.Mask" user "Board Geometry/Soldermask Top")
		(3 "B.Mask" user "Board Geometry/Soldermask Bottom")
		(17 "Dwgs.User" user "User.Drawings")
		(19 "Cmts.User" user "User.Comments")
		(21 "Eco1.User" user "User.Eco1")
		(23 "Eco2.User" user "User.Eco2")
		(25 "Edge.Cuts" user "Board Geometry/Outline")
		(27 "Margin" user)
		(31 "F.CrtYd" user "Package Geometry/Place Bound Top")
		(29 "B.CrtYd" user "Package Geometry/Place Bound Bottom")
		(35 "F.Fab" user "Ref Des/Assembly Top")
		(33 "B.Fab" user "Ref Des/Assembly Bottom")
	)
	(footprint ""
		(layer "F.Cu")
		(at 416.347148 -258.091686)
		(property "Reference" "J9"
			(at -3.683 -81.702148 0)
			(unlocked yes)
			(layer "F.SilkS")
			(effects
				(font
					(size 0.7874 0.5842)
					(thickness 0.1524)
				)
				(justify left)
			)
		)
		(property "Value" ""
			(at 0 0 0)
			(layer "F.Fab")
			(effects
				(font
					(size 1.27 1.27)
				)
			)
		)
		(duplicate_pad_numbers_are_jumpers no)
		(pad "92" smd rect
			(at -2.050034 19.12493 270)
			(size 0.519938 1.4986)
			(layers "F.Cu" "F.Mask" "F.Paste")
			(net "GND")
		)
		(pad "93" smd rect
			(at -2.050034 19.975068 270)
			(size 0.519938 1.4986)
			(layers "F.Cu" "F.Mask" "F.Paste")
			(net "M_E_CPU0_SB_DQS_DP<9>")
		)
		(pad "94" smd rect
			(at -2.050034 20.824952 270)
			(size 0.519938 1.4986)
			(layers "F.Cu" "F.Mask" "F.Paste")
			(net "M_E_CPU0_SB_DQS_DN<9>")
		)
		(pad "95" smd rect
			(at -2.050034 21.67509 270)
			(size 0.519938 1.4986)
			(layers "F.Cu" "F.Mask" "F.Paste")
			(net "GND")
		)
		(pad "96" smd rect
			(at -2.050034 22.524974 270)
			(size 0.519938 1.4986)
			(layers "F.Cu" "F.Mask" "F.Paste")
			(net "M_E_CPU0_SB_CB<0>")
		)
		(pad "97" smd rect
			(at -2.050034 23.375112 270)
			(size 0.519938 1.4986)
			(layers "F.Cu" "F.Mask" "F.Paste")
			(net "GND")
		)
		(pad "98" smd rect
			(at -2.050034 24.224996 270)
			(size 0.519938 1.4986)
			(layers "F.Cu" "F.Mask" "F.Paste")
			(net "M_E_CPU0_SB_CB<1>")
		)
		(pad "99" smd rect
			(at -2.050034 25.07488 270)
			(size 0.519938 1.4986)
			(layers "F.Cu" "F.Mask" "F.Paste")
			(net "GND")
		)
		(pad "100" smd rect
			(at -2.050034 25.925018 270)
			(size 0.519938 1.4986)
			(layers "F.Cu" "F.Mask" "F.Paste")
			(net "M_E_CPU0_SB_DQ<0>")
		)
		(pad "101" smd rect
			(at -2.050034 26.774902 270)
			(size 0.519938 1.4986)
			(layers "F.Cu" "F.Mask" "F.Paste")
			(net "GND")
		)
		(pad "102" smd rect
			(at -2.050034 27.62504 270)
			(size 0.519938 1.4986)
			(layers "F.Cu" "F.Mask" "F.Paste")
			(net "M_E_CPU0_SB_DQ<1>")
		)
		(pad "103" smd rect
			(at -2.050034 28.474924 270)
			(size 0.519938 1.4986)
			(layers "F.Cu" "F.Mask" "F.Paste")
			(net "GND")
		)
		(pad "104" smd rect
			(at -2.050034 29.325062 270)
			(size 0.519938 1.4986)
			(layers "F.Cu" "F.Mask" "F.Paste")
			(net "M_E_CPU0_SB_DQS_DP<0>")
		)
		(pad "105" smd rect
			(at -2.050034 30.174946 270)
			(size 0.519938 1.4986)
			(layers "F.Cu" "F.Mask" "F.Paste")
			(net "M_E_CPU0_SB_DQS_DN<0>")
		)
		(pad "106" smd rect
			(at -2.050034 31.025084 270)
			(size 0.519938 1.4986)
			(layers "F.Cu" "F.Mask" "F.Paste")
			(net "GND")
		)
		(pad "107" smd rect
			(at -2.050034 31.874968 270)
			(size 0.519938 1.4986)
			(layers "F.Cu" "F.Mask" "F.Paste")
			(net "M_E_CPU0_SB_DQ<4>")
		)
		(pad "108" smd rect
			(at -2.050034 32.725106 270)
			(size 0.519938 1.4986)
			(layers "F.Cu" "F.Mask" "F.Paste")
			(net "GND")
		)
		(pad "109" smd rect
			(at -2.050034 33.57499 270)
			(size 0.519938 1.4986)
			(layers "F.Cu" "F.Mask" "F.Paste")
			(net "M_E_CPU0_SB_DQ<5>")
		)
		(pad "110" smd rect
			(at -2.050034 34.425128 270)
			(size 0.519938 1.4986)
			(layers "F.Cu" "F.Mask" "F.Paste")
			(net "GND")
		)
		(pad "111" smd rect
			(at -2.050034 35.275012 270)
			(size 0.519938 1.4986)
			(layers "F.Cu" "F.Mask" "F.Paste")
			(net "M_E_CPU0_SB_DQ<8>")
		)
		(pad "112" smd rect
			(at -2.050034 36.124896 270)
			(size 0.519938 1.4986)
			(layers "F.Cu" "F.Mask" "F.Paste")
			(net "GND")
		)
		(pad "113" smd rect
			(at -2.050034 36.975034 270)
			(size 0.519938 1.4986)
			(layers "F.Cu" "F.Mask" "F.Paste")
			(net "M_E_CPU0_SB_DQ<9>")
		)
		(pad "114" smd rect
			(at -2.050034 37.824918 270)
			(size 0.519938 1.4986)
			(layers "F.Cu" "F.Mask" "F.Paste")
			(net "GND")
		)
		(pad "115" smd rect
			(at -2.050034 38.675056 270)
			(size 0.519938 1.4986)
			(layers "F.Cu" "F.Mask" "F.Paste")
			(net "M_E_CPU0_SB_DQS_DP<1>")
		)
		(pad "116" smd rect
			(at -2.050034 39.52494 270)
			(size 0.519938 1.4986)
			(layers "F.Cu" "F.Mask" "F.Paste")
			(net "M_E_CPU0_SB_DQS_DN<1>")
		)
		(pad "117" smd rect
			(at -2.050034 40.375078 270)
			(size 0.519938 1.4986)
			(layers "F.Cu" "F.Mask" "F.Paste")
			(net "GND")
		)
		(pad "118" smd rect
			(at -2.050034 41.224962 270)
			(size 0.519938 1.4986)
			(layers "F.Cu" "F.Mask" "F.Paste")
			(net "M_E_CPU0_SB_DQ<12>")
		)
		(pad "119" smd rect
			(at -2.050034 42.0751 270)
			(size 0.519938 1.4986)
			(layers "F.Cu" "F.Mask" "F.Paste")
			(net "GND")
		)
		(pad "120" smd rect
			(at -2.050034 42.924984 270)
			(size 0.519938 1.4986)
			(layers "F.Cu" "F.Mask" "F.Paste")
			(net "M_E_CPU0_SB_DQ<13>")
		)
		(pad "121" smd rect
			(at -2.050034 43.775122 270)
			(size 0.519938 1.4986)
			(layers "F.Cu" "F.Mask" "F.Paste")
			(net "GND")
		)
		(pad "122" smd rect
			(at -2.050034 44.625006 270)
			(size 0.519938 1.4986)
			(layers "F.Cu" "F.Mask" "F.Paste")
			(net "M_E_CPU0_SB_DQ<16>")
		)
		(pad "123" smd rect
			(at -2.050034 45.47489 270)
			(size 0.519938 1.4986)
			(layers "F.Cu" "F.Mask" "F.Paste")
			(net "GND")
		)
		(pad "124" smd rect
			(at -2.050034 46.325028 270)
			(size 0.519938 1.4986)
			(layers "F.Cu" "F.Mask" "F.Paste")
			(net "M_E_CPU0_SB_DQ<17>")
		)
		(pad "125" smd rect
			(at -2.050034 47.174912 270)
			(size 0.519938 1.4986)
			(layers "F.Cu" "F.Mask" "F.Paste")
			(net "GND")
		)
		(pad "126" smd rect
			(at -2.050034 48.02505 270)
			(size 0.519938 1.4986)
			(layers "F.Cu" "F.Mask" "F.Paste")
			(net "M_E_CPU0_SB_DQS_DP<2>")
		)
		(pad "127" smd rect
			(at -2.050034 48.874934 270)
			(size 0.519938 1.4986)
			(layers "F.Cu" "F.Mask" "F.Paste")
			(net "M_E_CPU0_SB_DQS_DN<2>")
		)
		(pad "128" smd rect
			(at -2.050034 49.725072 270)
			(size 0.519938 1.4986)
			(layers "F.Cu" "F.Mask" "F.Paste")
			(net "GND")
		)
		(pad "129" smd rect
			(at -2.050034 50.574956 270)
			(size 0.519938 1.4986)
			(layers "F.Cu" "F.Mask" "F.Paste")
			(net "M_E_CPU0_SB_DQ<20>")
		)
		(pad "130" smd rect
			(at -2.050034 51.425094 270)
			(size 0.519938 1.4986)
			(layers "F.Cu" "F.Mask" "F.Paste")
			(net "GND")
		)
		(pad "131" smd rect
			(at -2.050034 52.274978 270)
			(size 0.519938 1.4986)
			(layers "F.Cu" "F.Mask" "F.Paste")
			(net "M_E_CPU0_SB_DQ<21>")
		)
		(pad "132" smd rect
			(at -2.050034 53.125116 270)
			(size 0.519938 1.4986)
			(layers "F.Cu" "F.Mask" "F.Paste")
			(net "GND")
		)
		(pad "133" smd rect
			(at -2.050034 53.975 270)
			(size 0.519938 1.4986)
			(layers "F.Cu" "F.Mask" "F.Paste")
			(net "M_E_CPU0_SB_DQ<24>")
		)
		(pad "134" smd rect
			(at -2.050034 54.824884 270)
			(size 0.519938 1.4986)
			(layers "F.Cu" "F.Mask" "F.Paste")
			(net "GND")
		)
		(pad "135" smd rect
			(at -2.050034 55.675022 270)
			(size 0.519938 1.4986)
			(layers "F.Cu" "F.Mask" "F.Paste")
			(net "M_E_CPU0_SB_DQ<25>")
		)
		(pad "136" smd rect
			(at -2.050034 56.524906 270)
			(size 0.519938 1.4986)
			(layers "F.Cu" "F.Mask" "F.Paste")
			(net "GND")
		)
		(pad "137" smd rect
			(at -2.050034 57.375044 270)
			(size 0.519938 1.4986)
			(layers "F.Cu" "F.Mask" "F.Paste")
			(net "M_E_CPU0_SB_DQS_DP<3>")
		)
	)
)
